# S9S_MB_2U (Grand Teton) — schematic netlist excerpt (pin names and nets, part order shuffled) for the footprints in the layout excerpt that follows; sources: Cadence DE-HDL packaged netlist, KiCad conversion of 03242023_DA0F0TMBIJ0_F0T_Motherboard_J_brd_V01_OCP.brd

PC2091  Q_CAP  0.1UF 25V 10% X7R  pkg 0402  page 156 : A = P3V3_OCP_SFF_R ; B = GND
PC607  Q_CAP  100NF 50V 10% X7R  pkg C0402  page 271 : A = SW_PVCCFA_EHV_FIVRA_CPU0_BOOT2_ ; B = SW_PVCCFA_EHV_FIVRA_CPU0_BOOTR2

(kicad_pcb
	(version 20260206)
	(generator "pcbnew")
	(generator_version "10.0")
	(general
		(thickness 1.6)
		(legacy_teardrops no)
	)
	(paper "A4")
	(title_block
		(title "03242023_DA0F0TMBIJ0_F0T_Motherboard_J_brd_V01_OCP.brd")
		(comment 1 "Grand Teton / footprints 4039-4040 of 6105")
	)
	(layers
		(0 "F.Cu" signal "TOP")
		(4 "In1.Cu" signal "GND")
		(6 "In2.Cu" signal "IN1")
		(8 "In3.Cu" signal "GND1")
		(10 "In4.Cu" signal "IN2")
		(12 "In5.Cu" signal "GND2")
		(14 "In6.Cu" signal "IN3")
		(16 "In7.Cu" signal "GND3")
		(18 "In8.Cu" signal "VCC")
		(20 "In9.Cu" signal "VCC1")
		(22 "In10.Cu" signal "GND4")
		(24 "In11.Cu" signal "IN4")
		(26 "In12.Cu" signal "GND5")
		(28 "In13.Cu" signal "IN5")
		(30 "In14.Cu" signal "GND6")
		(32 "In15.Cu" signal "IN6")
		(34 "In16.Cu" signal "GND7")
		(2 "B.Cu" signal "BOTTOM")
		(9 "F.Adhes" user "F.Adhesive")
		(11 "B.Adhes" user "B.Adhesive")
		(13 "F.Paste" user "Package Geometry/Pastemask Top")
		(15 "B.Paste" user "Package Geometry/Pastemask Bottom")
		(5 "F.SilkS" user "Ref Des/Silkscreen Top")
		(7 "B.SilkS" user "Ref Des/Silkscreen Bottom")
		(1 "F.Mask" user "Board Geometry/Soldermask Top")
		(3 "B.Mask" user "Board Geometry/Soldermask Bottom")
		(17 "Dwgs.User" user "User.Drawings")
		(19 "Cmts.User" user "User.Comments")
		(21 "Eco1.User" user "User.Eco1")
		(23 "Eco2.User" user "User.Eco2")
		(25 "Edge.Cuts" user "Board Geometry/Outline")
		(27 "Margin" user)
		(31 "F.CrtYd" user "Package Geometry/Place Bound Top")
		(29 "B.CrtYd" user "Package Geometry/Place Bound Bottom")
		(35 "F.Fab" user "Ref Des/Assembly Top")
		(33 "B.Fab" user "Ref Des/Assembly Bottom")
	)
	(footprint ""
		(layer "F.Cu")
		(at 300.260258 -367.378996 -90)
		(property "Reference" "PC607"
			(at 0 0 270)
			(layer "F.SilkS")
			(hide yes)
			(effects
				(font
					(size 1.27 1.27)
				)
			)
		)
		(property "Value" ""
			(at 0 0 270)
			(layer "F.Fab")
			(effects
				(font
					(size 1.27 1.27)
				)
			)
		)
		(duplicate_pad_numbers_are_jumpers no)
		(fp_line
			(start -0.7874 0.4064)
			(end -0.7874 -0.4064)
			(stroke
				(width 0.1524)
				(type default)
			)
			(layer "F.SilkS")
		)
		(fp_line
			(start 0.7874 0.4064)
			(end -0.7874 0.4064)
			(stroke
				(width 0.1524)
				(type default)
			)
			(layer "F.SilkS")
		)
		(fp_line
			(start -0.7874 -0.4064)
			(end 0.7874 -0.4064)
			(stroke
				(width 0.1524)
				(type default)
			)
			(layer "F.SilkS")
		)
		(fp_line
			(start 0.7874 -0.4064)
			(end 0.7874 0.4064)
			(stroke
				(width 0.1524)
				(type default)
			)
			(layer "F.SilkS")
		)
		(fp_line
			(start -0.67945 0.3048)
			(end -0.67945 -0.305054)
			(stroke
				(width 0.1)
				(type default)
			)
			(layer "F.Fab")
		)
		(fp_line
			(start -0.12065 0.3048)
			(end -0.67945 0.3048)
			(stroke
				(width 0.1)
				(type default)
			)
			(layer "F.Fab")
		)
		(fp_line
			(start 0.120396 0.3048)
			(end 0.120396 0.2794)
			(stroke
				(width 0.1)
				(type default)
			)
			(layer "F.Fab")
		)
		(fp_line
			(start 0.67945 0.3048)
			(end 0.120396 0.3048)
			(stroke
				(width 0.1)
				(type default)
			)
			(layer "F.Fab")
		)
		(fp_line
			(start -0.12065 0.2794)
			(end -0.12065 0.3048)
			(stroke
				(width 0.1)
				(type default)
			)
			(layer "F.Fab")
		)
		(fp_line
			(start 0.120396 0.2794)
			(end -0.12065 0.2794)
			(stroke
				(width 0.1)
				(type default)
			)
			(layer "F.Fab")
		)
		(fp_line
			(start -0.12065 -0.2794)
			(end 0.12065 -0.2794)
			(stroke
				(width 0.1)
				(type default)
			)
			(layer "F.Fab")
		)
		(fp_line
			(start 0.12065 -0.2794)
			(end 0.12065 -0.3048)
			(stroke
				(width 0.1)
				(type default)
			)
			(layer "F.Fab")
		)
		(fp_line
			(start 0.12065 -0.3048)
			(end 0.67945 -0.3048)
			(stroke
				(width 0.1)
				(type default)
			)
			(layer "F.Fab")
		)
		(fp_line
			(start 0.67945 -0.3048)
			(end 0.67945 0.3048)
			(stroke
				(width 0.1)
				(type default)
			)
			(layer "F.Fab")
		)
		(fp_line
			(start -0.67945 -0.305054)
			(end -0.12065 -0.305054)
			(stroke
				(width 0.1)
				(type default)
			)
			(layer "F.Fab")
		)
		(fp_line
			(start -0.12065 -0.305054)
			(end -0.12065 -0.2794)
			(stroke
				(width 0.1)
				(type default)
			)
			(layer "F.Fab")
		)
		(pad "1" smd circle
			(at -0.40005 0 270)
			(size 0 0)
			(layers "F.Cu" "F.Mask" "F.Paste")
			(net "SW_PVCCFA_EHV_FIVRA_CPU0_BOOT2_")
		)
		(pad "2" smd circle
			(at 0.40005 0 270)
			(size 0 0)
			(layers "F.Cu" "F.Mask" "F.Paste")
			(net "SW_PVCCFA_EHV_FIVRA_CPU0_BOOTR2")
		)
	)
	(footprint ""
		(layer "F.Cu")
		(at 425.163488 -109.12983 90)
		(property "Reference" "PC2091"
			(at 0 0 90)
			(layer "F.SilkS")
			(hide yes)
			(effects
				(font
					(size 1.27 1.27)
				)
			)
		)
		(property "Value" ""
			(at 0 0 90)
			(layer "F.Fab")
			(effects
				(font
					(size 1.27 1.27)
				)
			)
		)
		(duplicate_pad_numbers_are_jumpers no)
		(fp_line
			(start 0.7874 -0.4064)
			(end 0.7874 0.4064)
			(stroke
				(width 0.1524)
				(type default)
			)
			(layer "F.SilkS")
		)
		(fp_line
			(start -0.7874 -0.4064)
			(end 0.7874 -0.4064)
			(stroke
				(width 0.1524)
				(type default)
			)
			(layer "F.SilkS")
		)
		(fp_line
			(start 0.7874 0.4064)
			(end -0.7874 0.4064)
			(stroke
				(width 0.1524)
				(type default)
			)
			(layer "F.SilkS")
		)
		(fp_line
			(start -0.7874 0.4064)
			(end -0.7874 -0.4064)
			(stroke
				(width 0.1524)
				(type default)
			)
			(layer "F.SilkS")
		)
		(fp_line
			(start -0.12065 -0.305054)
			(end -0.12065 -0.2794)
			(stroke
				(width 0.1)
				(type default)
			)
			(layer "F.Fab")
		)
		(fp_line
			(start -0.67945 -0.305054)
			(end -0.12065 -0.305054)
			(stroke
				(width 0.1)
				(type default)
			)
			(layer "F.Fab")
		)
		(fp_line
			(start 0.67945 -0.3048)
			(end 0.67945 0.3048)
			(stroke
				(width 0.1)
				(type default)
			)
			(layer "F.Fab")
		)
		(fp_line
			(start 0.12065 -0.3048)
			(end 0.67945 -0.3048)
			(stroke
				(width 0.1)
				(type default)
			)
			(layer "F.Fab")
		)
		(fp_line
			(start 0.12065 -0.2794)
			(end 0.12065 -0.3048)
			(stroke
				(width 0.1)
				(type default)
			)
			(layer "F.Fab")
		)
		(fp_line
			(start -0.12065 -0.2794)
			(end 0.12065 -0.2794)
			(stroke
				(width 0.1)
				(type default)
			)
			(layer "F.Fab")
		)
		(fp_line
			(start 0.120396 0.2794)
			(end -0.12065 0.2794)
			(stroke
				(width 0.1)
				(type default)
			)
			(layer "F.Fab")
		)
		(fp_line
			(start -0.12065 0.2794)
			(end -0.12065 0.3048)
			(stroke
				(width 0.1)
				(type default)
			)
			(layer "F.Fab")
		)
		(fp_line
			(start 0.67945 0.3048)
			(end 0.120396 0.3048)
			(stroke
				(width 0.1)
				(type default)
			)
			(layer "F.Fab")
		)
		(fp_line
			(start 0.120396 0.3048)
			(end 0.120396 0.2794)
			(stroke
				(width 0.1)
				(type default)
			)
			(layer "F.Fab")
		)
		(fp_line
			(start -0.12065 0.3048)
			(end -0.67945 0.3048)
			(stroke
				(width 0.1)
				(type default)
			)
			(layer "F.Fab")
		)
		(fp_line
			(start -0.67945 0.3048)
			(end -0.67945 -0.305054)
			(stroke
				(width 0.1)
				(type default)
			)
			(layer "F.Fab")
		)
		(pad "1" smd circle
			(at -0.40005 0 90)
			(size 0 0)
			(layers "F.Cu" "F.Mask" "F.Paste")
			(net "P3V3_OCP_SFF_R")
		)
		(pad "2" smd circle
			(at 0.40005 0 90)
			(size 0 0)
			(layers "F.Cu" "F.Mask" "F.Paste")
			(net "GND")
		)
	)
)
